(kicad_pcb
	(version 20260206)
	(generator "pcbnew")
	(generator_version "10.0")
	(general
		(thickness 1.6)
		(legacy_teardrops no)
	)
	(paper "A4")
	(title_block
		(title "v1-chassis-manager — T6M_CM_d_v01_1031_1645.brd")
		(comment 1 "Open CloudServer (Microsoft) / footprints 1885-1894 of 2512")
	)
	(layers
		(0 "F.Cu" signal "TOP")
		(4 "In1.Cu" signal "GND1")
		(6 "In2.Cu" signal "IN1")
		(8 "In3.Cu" signal "VCC1")
		(10 "In4.Cu" signal "VCC2")
		(12 "In5.Cu" signal "GND2")
		(14 "In6.Cu" signal "IN2")
		(16 "In7.Cu" signal "IN3")
		(18 "In8.Cu" signal "GND3")
		(2 "B.Cu" signal "BOTTOM")
		(9 "F.Adhes" user "F.Adhesive")
		(11 "B.Adhes" user "B.Adhesive")
		(13 "F.Paste" user "Package Geometry/Pastemask Top")
		(15 "B.Paste" user "Package Geometry/Pastemask Bottom")
		(5 "F.SilkS" user "Ref Des/Silkscreen Top")
		(7 "B.SilkS" user "Ref Des/Silkscreen Bottom")
		(1 "F.Mask" user "Board Geometry/Soldermask Top")
		(3 "B.Mask" user "Board Geometry/Soldermask Bottom")
		(17 "Dwgs.User" user "User.Drawings")
		(19 "Cmts.User" user "User.Comments")
		(21 "Eco1.User" user "User.Eco1")
		(23 "Eco2.User" user "User.Eco2")
		(25 "Edge.Cuts" user "Board Geometry/Outline")
		(27 "Margin" user)
		(31 "F.CrtYd" user "Package Geometry/Place Bound Top")
		(29 "B.CrtYd" user "Package Geometry/Place Bound Bottom")
		(35 "F.Fab" user "Ref Des/Assembly Top")
		(33 "B.Fab" user "Ref Des/Assembly Bottom")
	)
	(footprint ""
		(layer "B.Cu")
		(at 144.909032 -37.694616)
		(property "Reference" "R1077"
			(at 1.24714 17.425924 0)
			(unlocked yes)
			(layer "B.SilkS")
			(effects
				(font
					(size 0.7874 0.5842)
					(thickness 0.1524)
				)
				(justify left mirror)
			)
		)
		(property "Value" ""
			(at 0 0 0)
			(layer "B.Fab")
			(effects
				(font
					(size 1.27 1.27)
				)
				(justify mirror)
			)
		)
		(duplicate_pad_numbers_are_jumpers no)
		(fp_line
			(start -0.7874 -0.4064)
			(end -0.7874 0.4064)
			(stroke
				(width 0.1524)
				(type default)
			)
			(layer "B.SilkS")
		)
		(fp_line
			(start -0.7874 0.4064)
			(end 0.7874 0.4064)
			(stroke
				(width 0.1524)
				(type default)
			)
			(layer "B.SilkS")
		)
		(fp_line
			(start 0.7874 -0.4064)
			(end -0.7874 -0.4064)
			(stroke
				(width 0.1524)
				(type default)
			)
			(layer "B.SilkS")
		)
		(fp_line
			(start 0.7874 0.4064)
			(end 0.7874 -0.4064)
			(stroke
				(width 0.1524)
				(type default)
			)
			(layer "B.SilkS")
		)
		(fp_poly
			(pts
				(xy 0.508 0.2794) (xy 0.508 0.2286) (xy 0.635 0.2286) (xy 0.635 -0.254) (xy 0.5334 -0.254) (xy 0.5334 -0.2794)
				(xy -0.5334 -0.2794) (xy -0.5334 -0.254) (xy -0.635 -0.254) (xy -0.635 0.254) (xy -0.5334 0.254)
				(xy -0.5334 0.2794)
			)
			(stroke
				(width 0)
				(type default)
			)
			(fill no)
			(layer "B.CrtYd")
		)
		(pad "1" smd rect
			(at -0.40005 0 180)
			(size 0.4572 0.508)
			(layers "B.Cu" "B.Mask" "B.Paste")
			(net "SIO_JTAG_CPLD2_TDI_R")
		)
		(pad "2" smd rect
			(at 0.40005 0 180)
			(size 0.4572 0.508)
			(layers "B.Cu" "B.Mask" "B.Paste")
			(net "P3V3_NODE1")
		)
	)
	(footprint ""
		(layer "B.Cu")
		(at 55.10276 -188.126624 90)
		(property "Reference" "R907"
			(at 4.276598 0.197104 270)
			(unlocked yes)
			(layer "B.SilkS")
			(effects
				(font
					(size 0.7874 0.5842)
					(thickness 0.1524)
				)
				(justify left mirror)
			)
		)
		(property "Value" ""
			(at 0 0 90)
			(layer "B.Fab")
			(effects
				(font
					(size 1.27 1.27)
				)
				(justify mirror)
			)
		)
		(duplicate_pad_numbers_are_jumpers no)
		(fp_line
			(start 0.7874 -0.4064)
			(end -0.7874 -0.4064)
			(stroke
				(width 0.1524)
				(type default)
			)
			(layer "B.SilkS")
		)
		(fp_line
			(start -0.7874 -0.4064)
			(end -0.7874 0.4064)
			(stroke
				(width 0.1524)
				(type default)
			)
			(layer "B.SilkS")
		)
		(fp_line
			(start 0.7874 0.4064)
			(end 0.7874 -0.4064)
			(stroke
				(width 0.1524)
				(type default)
			)
			(layer "B.SilkS")
		)
		(fp_line
			(start -0.7874 0.4064)
			(end 0.7874 0.4064)
			(stroke
				(width 0.1524)
				(type default)
			)
			(layer "B.SilkS")
		)
		(fp_poly
			(pts
				(xy 0.508 0.2794) (xy 0.508 0.2286) (xy 0.635 0.2286) (xy 0.635 -0.254) (xy 0.5334 -0.254) (xy 0.5334 -0.2794)
				(xy -0.5334 -0.2794) (xy -0.5334 -0.254) (xy -0.635 -0.254) (xy -0.635 0.254) (xy -0.5334 0.254)
				(xy -0.5334 0.2794)
			)
			(stroke
				(width 0)
				(type default)
			)
			(fill no)
			(layer "B.CrtYd")
		)
		(pad "1" smd rect
			(at -0.40005 0 270)
			(size 0.4572 0.508)
			(layers "B.Cu" "B.Mask" "B.Paste")
			(net "UART_T1_NODE1_RXD")
		)
		(pad "2" smd rect
			(at 0.40005 0 270)
			(size 0.4572 0.508)
			(layers "B.Cu" "B.Mask" "B.Paste")
			(net "UART_T1_NODE1_RXD_R")
		)
	)
	(footprint ""
		(layer "B.Cu")
		(at 48.758602 -152.128982 180)
		(property "Reference" "C405"
			(at 11.821922 5.554218 0)
			(unlocked yes)
			(layer "B.SilkS")
			(effects
				(font
					(size 0.7874 0.5842)
					(thickness 0.1524)
				)
				(justify left mirror)
			)
		)
		(property "Value" ""
			(at 0 0 0)
			(layer "B.Fab")
			(effects
				(font
					(size 1.27 1.27)
				)
				(justify mirror)
			)
		)
		(duplicate_pad_numbers_are_jumpers no)
		(fp_line
			(start 0.7874 0.4064)
			(end 0.7874 -0.4064)
			(stroke
				(width 0.1524)
				(type default)
			)
			(layer "B.SilkS")
		)
		(fp_line
			(start 0.7874 -0.4064)
			(end -0.7874 -0.4064)
			(stroke
				(width 0.1524)
				(type default)
			)
			(layer "B.SilkS")
		)
		(fp_line
			(start 0 0.381)
			(end 0 -0.381)
			(stroke
				(width 0.1524)
				(type default)
			)
			(layer "B.SilkS")
		)
		(fp_line
			(start -0.7874 0.4064)
			(end 0.7874 0.4064)
			(stroke
				(width 0.1524)
				(type default)
			)
			(layer "B.SilkS")
		)
		(fp_line
			(start -0.7874 -0.4064)
			(end -0.7874 0.4064)
			(stroke
				(width 0.1524)
				(type default)
			)
			(layer "B.SilkS")
		)
		(fp_poly
			(pts
				(xy 0.5334 0.254) (xy 0.635 0.254) (xy 0.635 0.2286) (xy 0.635 -0.254) (xy 0.5334 -0.254) (xy 0.5334 -0.2794)
				(xy -0.5334 -0.2794) (xy -0.5334 -0.254) (xy -0.635 -0.254) (xy -0.635 0.254) (xy -0.5334 0.254)
				(xy -0.5334 0.2794) (xy 0.508 0.2794) (xy 0.5334 0.2794)
			)
			(stroke
				(width 0)
				(type default)
			)
			(fill no)
			(layer "B.CrtYd")
		)
		(pad "1" smd rect
			(at -0.40005 0)
			(size 0.4572 0.508)
			(layers "B.Cu" "B.Mask" "B.Paste")
			(net "P1V9_LAN1")
		)
		(pad "2" smd rect
			(at 0.40005 0)
			(size 0.4572 0.508)
			(layers "B.Cu" "B.Mask" "B.Paste")
			(net "GND")
		)
	)
	(footprint ""
		(layer "B.Cu")
		(at 154.77363 -169.763948 90)
		(property "Reference" "C915"
			(at -4.011422 -0.368046 270)
			(unlocked yes)
			(layer "B.SilkS")
			(effects
				(font
					(size 0.7874 0.5842)
					(thickness 0.1524)
				)
				(justify left mirror)
			)
		)
		(property "Value" ""
			(at 0 0 90)
			(layer "B.Fab")
			(effects
				(font
					(size 1.27 1.27)
				)
				(justify mirror)
			)
		)
		(duplicate_pad_numbers_are_jumpers no)
		(fp_line
			(start 0.7874 -0.4064)
			(end -0.7874 -0.4064)
			(stroke
				(width 0.1524)
				(type default)
			)
			(layer "B.SilkS")
		)
		(fp_line
			(start -0.7874 -0.4064)
			(end -0.7874 0.4064)
			(stroke
				(width 0.1524)
				(type default)
			)
			(layer "B.SilkS")
		)
		(fp_line
			(start 0 0.381)
			(end 0 -0.381)
			(stroke
				(width 0.1524)
				(type default)
			)
			(layer "B.SilkS")
		)
		(fp_line
			(start 0.7874 0.4064)
			(end 0.7874 -0.4064)
			(stroke
				(width 0.1524)
				(type default)
			)
			(layer "B.SilkS")
		)
		(fp_line
			(start -0.7874 0.4064)
			(end 0.7874 0.4064)
			(stroke
				(width 0.1524)
				(type default)
			)
			(layer "B.SilkS")
		)
		(fp_poly
			(pts
				(xy 0.5334 0.254) (xy 0.635 0.254) (xy 0.635 0.2286) (xy 0.635 -0.254) (xy 0.5334 -0.254) (xy 0.5334 -0.2794)
				(xy -0.5334 -0.2794) (xy -0.5334 -0.254) (xy -0.635 -0.254) (xy -0.635 0.254) (xy -0.5334 0.254)
				(xy -0.5334 0.2794) (xy 0.508 0.2794) (xy 0.5334 0.2794)
			)
			(stroke
				(width 0)
				(type default)
			)
			(fill no)
			(layer "B.CrtYd")
		)
		(pad "1" smd rect
			(at -0.40005 0 270)
			(size 0.4572 0.508)
			(layers "B.Cu" "B.Mask" "B.Paste")
			(net "N54365827")
		)
		(pad "2" smd rect
			(at 0.40005 0 270)
			(size 0.4572 0.508)
			(layers "B.Cu" "B.Mask" "B.Paste")
			(net "N54365829")
		)
	)
	(footprint ""
		(layer "B.Cu")
		(at 147.104354 -178.784504 90)
		(property "Reference" "R744"
			(at 1.337818 -0.313944 270)
			(unlocked yes)
			(layer "B.SilkS")
			(effects
				(font
					(size 0.7874 0.5842)
					(thickness 0.1524)
				)
				(justify left mirror)
			)
		)
		(property "Value" ""
			(at 0 0 90)
			(layer "B.Fab")
			(effects
				(font
					(size 1.27 1.27)
				)
				(justify mirror)
			)
		)
		(duplicate_pad_numbers_are_jumpers no)
		(fp_line
			(start 0.7874 -0.4064)
			(end -0.7874 -0.4064)
			(stroke
				(width 0.1524)
				(type default)
			)
			(layer "B.SilkS")
		)
		(fp_line
			(start -0.7874 -0.4064)
			(end -0.7874 0.4064)
			(stroke
				(width 0.1524)
				(type default)
			)
			(layer "B.SilkS")
		)
		(fp_line
			(start 0.7874 0.4064)
			(end 0.7874 -0.4064)
			(stroke
				(width 0.1524)
				(type default)
			)
			(layer "B.SilkS")
		)
		(fp_line
			(start -0.7874 0.4064)
			(end 0.7874 0.4064)
			(stroke
				(width 0.1524)
				(type default)
			)
			(layer "B.SilkS")
		)
		(fp_poly
			(pts
				(xy 0.508 0.2794) (xy 0.508 0.2286) (xy 0.635 0.2286) (xy 0.635 -0.254) (xy 0.5334 -0.254) (xy 0.5334 -0.2794)
				(xy -0.5334 -0.2794) (xy -0.5334 -0.254) (xy -0.635 -0.254) (xy -0.635 0.254) (xy -0.5334 0.254)
				(xy -0.5334 0.2794)
			)
			(stroke
				(width 0)
				(type default)
			)
			(fill no)
			(layer "B.CrtYd")
		)
		(pad "1" smd rect
			(at -0.40005 0 270)
			(size 0.4572 0.508)
			(layers "B.Cu" "B.Mask" "B.Paste")
			(net "T11_NODE3_EN")
		)
		(pad "2" smd rect
			(at 0.40005 0 270)
			(size 0.4572 0.508)
			(layers "B.Cu" "B.Mask" "B.Paste")
			(net "P5V_NODE1")
		)
	)
	(footprint ""
		(layer "B.Cu")
		(at 61.965586 -138.166348)
		(property "Reference" "C244"
			(at -40.418004 52.882546 0)
			(unlocked yes)
			(layer "B.SilkS")
			(effects
				(font
					(size 0.7874 0.5842)
					(thickness 0.1524)
				)
				(justify left mirror)
			)
		)
		(property "Value" ""
			(at 0 0 0)
			(layer "B.Fab")
			(effects
				(font
					(size 1.27 1.27)
				)
				(justify mirror)
			)
		)
		(duplicate_pad_numbers_are_jumpers no)
		(fp_line
			(start -0.7874 -0.4064)
			(end -0.7874 0.4064)
			(stroke
				(width 0.1524)
				(type default)
			)
			(layer "B.SilkS")
		)
		(fp_line
			(start -0.7874 0.4064)
			(end 0.7874 0.4064)
			(stroke
				(width 0.1524)
				(type default)
			)
			(layer "B.SilkS")
		)
		(fp_line
			(start 0 0.381)
			(end 0 -0.381)
			(stroke
				(width 0.1524)
				(type default)
			)
			(layer "B.SilkS")
		)
		(fp_line
			(start 0.7874 -0.4064)
			(end -0.7874 -0.4064)
			(stroke
				(width 0.1524)
				(type default)
			)
			(layer "B.SilkS")
		)
		(fp_line
			(start 0.7874 0.4064)
			(end 0.7874 -0.4064)
			(stroke
				(width 0.1524)
				(type default)
			)
			(layer "B.SilkS")
		)
		(fp_poly
			(pts
				(xy 0.5334 0.254) (xy 0.635 0.254) (xy 0.635 0.2286) (xy 0.635 -0.254) (xy 0.5334 -0.254) (xy 0.5334 -0.2794)
				(xy -0.5334 -0.2794) (xy -0.5334 -0.254) (xy -0.635 -0.254) (xy -0.635 0.254) (xy -0.5334 0.254)
				(xy -0.5334 0.2794) (xy 0.508 0.2794) (xy 0.5334 0.2794)
			)
			(stroke
				(width 0)
				(type default)
			)
			(fill no)
			(layer "B.CrtYd")
		)
		(pad "1" smd rect
			(at -0.40005 0 180)
			(size 0.4572 0.508)
			(layers "B.Cu" "B.Mask" "B.Paste")
			(net "P3V3_NODE1")
		)
		(pad "2" smd rect
			(at 0.40005 0 180)
			(size 0.4572 0.508)
			(layers "B.Cu" "B.Mask" "B.Paste")
			(net "GND")
		)
	)
	(footprint ""
		(layer "B.Cu")
		(at 69.395086 -121.044462 90)
		(property "Reference" "R253"
			(at -7.37235 10.059162 270)
			(unlocked yes)
			(layer "B.SilkS")
			(effects
				(font
					(size 0.7874 0.5842)
					(thickness 0.1524)
				)
				(justify left mirror)
			)
		)
		(property "Value" ""
			(at 0 0 90)
			(layer "B.Fab")
			(effects
				(font
					(size 1.27 1.27)
				)
				(justify mirror)
			)
		)
		(duplicate_pad_numbers_are_jumpers no)
		(fp_line
			(start 0.7874 -0.4064)
			(end -0.7874 -0.4064)
			(stroke
				(width 0.1524)
				(type default)
			)
			(layer "B.SilkS")
		)
		(fp_line
			(start -0.7874 -0.4064)
			(end -0.7874 0.4064)
			(stroke
				(width 0.1524)
				(type default)
			)
			(layer "B.SilkS")
		)
		(fp_line
			(start 0.7874 0.4064)
			(end 0.7874 -0.4064)
			(stroke
				(width 0.1524)
				(type default)
			)
			(layer "B.SilkS")
		)
		(fp_line
			(start -0.7874 0.4064)
			(end 0.7874 0.4064)
			(stroke
				(width 0.1524)
				(type default)
			)
			(layer "B.SilkS")
		)
		(fp_poly
			(pts
				(xy 0.508 0.2794) (xy 0.508 0.2286) (xy 0.635 0.2286) (xy 0.635 -0.254) (xy 0.5334 -0.254) (xy 0.5334 -0.2794)
				(xy -0.5334 -0.2794) (xy -0.5334 -0.254) (xy -0.635 -0.254) (xy -0.635 0.254) (xy -0.5334 0.254)
				(xy -0.5334 0.2794)
			)
			(stroke
				(width 0)
				(type default)
			)
			(fill no)
			(layer "B.CrtYd")
		)
		(pad "1" smd rect
			(at -0.40005 0 270)
			(size 0.4572 0.508)
			(layers "B.Cu" "B.Mask" "B.Paste")
			(net "GND")
		)
		(pad "2" smd rect
			(at 0.40005 0 270)
			(size 0.4572 0.508)
			(layers "B.Cu" "B.Mask" "B.Paste")
			(net "RST_BMC_NODE1_PERST_L")
		)
	)
	(footprint ""
		(layer "B.Cu")
		(at 91.102434 -183.778398 180)
		(property "Reference" "R930"
			(at 2.352294 4.02082 0)
			(unlocked yes)
			(layer "B.SilkS")
			(effects
				(font
					(size 0.7874 0.5842)
					(thickness 0.1524)
				)
				(justify left mirror)
			)
		)
		(property "Value" ""
			(at 0 0 0)
			(layer "B.Fab")
			(effects
				(font
					(size 1.27 1.27)
				)
				(justify mirror)
			)
		)
		(duplicate_pad_numbers_are_jumpers no)
		(fp_line
			(start 0.7874 0.4064)
			(end 0.7874 -0.4064)
			(stroke
				(width 0.1524)
				(type default)
			)
			(layer "B.SilkS")
		)
		(fp_line
			(start 0.7874 -0.4064)
			(end -0.7874 -0.4064)
			(stroke
				(width 0.1524)
				(type default)
			)
			(layer "B.SilkS")
		)
		(fp_line
			(start -0.7874 0.4064)
			(end 0.7874 0.4064)
			(stroke
				(width 0.1524)
				(type default)
			)
			(layer "B.SilkS")
		)
		(fp_line
			(start -0.7874 -0.4064)
			(end -0.7874 0.4064)
			(stroke
				(width 0.1524)
				(type default)
			)
			(layer "B.SilkS")
		)
		(fp_poly
			(pts
				(xy 0.508 0.2794) (xy 0.508 0.2286) (xy 0.635 0.2286) (xy 0.635 -0.254) (xy 0.5334 -0.254) (xy 0.5334 -0.2794)
				(xy -0.5334 -0.2794) (xy -0.5334 -0.254) (xy -0.635 -0.254) (xy -0.635 0.254) (xy -0.5334 0.254)
				(xy -0.5334 0.2794)
			)
			(stroke
				(width 0)
				(type default)
			)
			(fill no)
			(layer "B.CrtYd")
		)
		(pad "1" smd rect
			(at -0.40005 0)
			(size 0.4572 0.508)
			(layers "B.Cu" "B.Mask" "B.Paste")
			(net "UART_T5_NODE4_TXD")
		)
		(pad "2" smd rect
			(at 0.40005 0)
			(size 0.4572 0.508)
			(layers "B.Cu" "B.Mask" "B.Paste")
			(net "UART_T5_NODE4_TXD_R")
		)
	)
	(footprint ""
		(layer "B.Cu")
		(at 171.180252 -98.59899 180)
		(property "Reference" "C368"
			(at -7.70509 0.042672 0)
			(unlocked yes)
			(layer "B.SilkS")
			(effects
				(font
					(size 0.7874 0.5842)
					(thickness 0.1524)
				)
				(justify left mirror)
			)
		)
		(property "Value" ""
			(at 0 0 0)
			(layer "B.Fab")
			(effects
				(font
					(size 1.27 1.27)
				)
				(justify mirror)
			)
		)
		(duplicate_pad_numbers_are_jumpers no)
		(fp_line
			(start 0.7874 0.4064)
			(end 0.7874 -0.4064)
			(stroke
				(width 0.1524)
				(type default)
			)
			(layer "B.SilkS")
		)
		(fp_line
			(start 0.7874 -0.4064)
			(end -0.7874 -0.4064)
			(stroke
				(width 0.1524)
				(type default)
			)
			(layer "B.SilkS")
		)
		(fp_line
			(start 0 0.381)
			(end 0 -0.381)
			(stroke
				(width 0.1524)
				(type default)
			)
			(layer "B.SilkS")
		)
		(fp_line
			(start -0.7874 0.4064)
			(end 0.7874 0.4064)
			(stroke
				(width 0.1524)
				(type default)
			)
			(layer "B.SilkS")
		)
		(fp_line
			(start -0.7874 -0.4064)
			(end -0.7874 0.4064)
			(stroke
				(width 0.1524)
				(type default)
			)
			(layer "B.SilkS")
		)
		(fp_poly
			(pts
				(xy 0.5334 0.254) (xy 0.635 0.254) (xy 0.635 0.2286) (xy 0.635 -0.254) (xy 0.5334 -0.254) (xy 0.5334 -0.2794)
				(xy -0.5334 -0.2794) (xy -0.5334 -0.254) (xy -0.635 -0.254) (xy -0.635 0.254) (xy -0.5334 0.254)
				(xy -0.5334 0.2794) (xy 0.508 0.2794) (xy 0.5334 0.2794)
			)
			(stroke
				(width 0)
				(type default)
			)
			(fill no)
			(layer "B.CrtYd")
		)
		(pad "1" smd rect
			(at -0.40005 0)
			(size 0.4572 0.508)
			(layers "B.Cu" "B.Mask" "B.Paste")
			(net "P1V05_NODE1")
		)
		(pad "2" smd rect
			(at 0.40005 0)
			(size 0.4572 0.508)
			(layers "B.Cu" "B.Mask" "B.Paste")
			(net "GND")
		)
	)
	(footprint ""
		(layer "B.Cu")
		(at 176.550828 -122.886724 90)
		(property "Reference" "C787"
			(at 2.881376 0.888492 270)
			(unlocked yes)
			(layer "B.SilkS")
			(effects
				(font
					(size 0.7874 0.5842)
					(thickness 0.1524)
				)
				(justify mirror)
			)
		)
		(property "Value" ""
			(at 0 0 90)
			(layer "B.Fab")
			(effects
				(font
					(size 1.27 1.27)
				)
				(justify mirror)
			)
		)
		(duplicate_pad_numbers_are_jumpers no)
		(fp_line
			(start 1.2954 -0.5842)
			(end -1.2954 -0.5842)
			(stroke
				(width 0.1524)
				(type default)
			)
			(layer "B.SilkS")
		)
		(fp_line
			(start 0 -0.5842)
			(end 0 0.5842)
			(stroke
				(width 0.1524)
				(type default)
			)
			(layer "B.SilkS")
		)
		(fp_line
			(start -1.2954 -0.5842)
			(end -1.2954 0.5842)
			(stroke
				(width 0.1524)
				(type default)
			)
			(layer "B.SilkS")
		)
		(fp_line
			(start 1.2954 0.5842)
			(end 1.2954 -0.5842)
			(stroke
				(width 0.1524)
				(type default)
			)
			(layer "B.SilkS")
		)
		(fp_line
			(start -1.2954 0.5842)
			(end 1.2954 0.5842)
			(stroke
				(width 0.1524)
				(type default)
			)
			(layer "B.SilkS")
		)
		(fp_poly
			(pts
				(xy -0.8636 -0.4572) (xy -0.8636 -0.3556) (xy -1.143 -0.3556) (xy -1.143 0.3556) (xy -0.8636 0.3556)
				(xy -0.8636 0.4572) (xy 0.8636 0.4572) (xy 0.8636 0.3556) (xy 1.143 0.3556) (xy 1.143 -0.3556) (xy 0.8636 -0.3556)
				(xy 0.8636 -0.4572)
			)
			(stroke
				(width 0)
				(type default)
			)
			(fill no)
			(layer "B.CrtYd")
		)
		(fp_line
			(start 0.884936 -0.504952)
			(end -0.884936 -0.504952)
			(stroke
				(width 0.1)
				(type default)
			)
			(layer "B.Fab")
		)
		(fp_line
			(start -0.884936 -0.504952)
			(end -0.884936 0.504952)
			(stroke
				(width 0.1)
				(type default)
			)
			(layer "B.Fab")
		)
		(fp_line
			(start 0.884936 0.504952)
			(end 0.884936 -0.504952)
			(stroke
				(width 0.1)
				(type default)
			)
			(layer "B.Fab")
		)
		(fp_line
			(start -0.884936 0.504952)
			(end 0.884936 0.504952)
			(stroke
				(width 0.1)
				(type default)
			)
			(layer "B.Fab")
		)
		(pad "1" smd rect
			(at -0.7366 0 180)
			(size 0.7112 0.8128)
			(layers "B.Cu" "B.Mask" "B.Paste")
			(net "P3V3_STB_NODE1")
		)
		(pad "2" smd rect
			(at 0.7366 0 180)
			(size 0.7112 0.8128)
			(layers "B.Cu" "B.Mask" "B.Paste")
			(net "GND")
		)
	)
)
